Design Name F:/<user>/2022/FB/R4006-TIMING/brd/gerber-3/R4006-B0001-02_R01.brd
Date  Feb 25 18:16:18 2022

Slot Hole Report
SLOT_TYPE SLOT_SIZE_MAJOR SLOT_SIZE_MINOR SLOT_X SLOT_Y SLOT_ROTATION SLOT_PLATING 
oval slot 63.0 24.0 248.07 3359.85 0.0 PLATED
oval slot 63.0 24.0 248.07 3472.45 0.0 PLATED
oval slot 63.0 24.0 437.05 3316.55 0.0 PLATED
oval slot 63.0 24.0 437.05 3515.76 0.0 PLATED
oval slot 51.0 24.0 6515.82 1972.44 180.0 PLATED
oval slot 51.0 24.0 6515.82 2248.04 180.0 PLATED
